# T6G (Grand Teton) — schematic netlist excerpt (pin names and nets, part order shuffled) for the footprints in the layout excerpt that follows; sources: Cadence DE-HDL packaged netlist, KiCad conversion of 04192023_DAF0TMB3IC0_F0TG_MB_C_brd_V02_OCP.brd

R6093  Q_RES  0 5% CHIP  pkg 0402LF  page 85 : A = SCM_SYS_PWROK_R ; B = SCM_SYS_PWROK_R2
C2458  Q_CAP  22UF 4V 20% X6S  pkg C0402  page 74 : A = PVDDCR_SOC_P1 ; B = GND

(kicad_pcb
	(version 20260206)
	(generator "pcbnew")
	(generator_version "10.0")
	(general
		(thickness 1.6)
		(legacy_teardrops no)
	)
	(paper "A4")
	(title_block
		(title "04192023_DAF0TMB3IC0_F0TG_MB_C_brd_V02_OCP.brd")
		(comment 1 "Grand Teton / footprints 5852-5853 of 8354")
	)
	(layers
		(0 "F.Cu" signal "TOP")
		(4 "In1.Cu" signal "GND")
		(6 "In2.Cu" signal "IN1")
		(8 "In3.Cu" signal "GND1")
		(10 "In4.Cu" signal "IN2")
		(12 "In5.Cu" signal "GND2")
		(14 "In6.Cu" signal "IN3")
		(16 "In7.Cu" signal "GND3")
		(18 "In8.Cu" signal "VCC")
		(20 "In9.Cu" signal "VCC1")
		(22 "In10.Cu" signal "GND4")
		(24 "In11.Cu" signal "IN4")
		(26 "In12.Cu" signal "GND5")
		(28 "In13.Cu" signal "IN5")
		(30 "In14.Cu" signal "GND6")
		(32 "In15.Cu" signal "IN6")
		(34 "In16.Cu" signal "GND7")
		(2 "B.Cu" signal "BOTTOM")
		(9 "F.Adhes" user "F.Adhesive")
		(11 "B.Adhes" user "B.Adhesive")
		(13 "F.Paste" user "Package Geometry/Pastemask Top")
		(15 "B.Paste" user "Package Geometry/Pastemask Bottom")
		(5 "F.SilkS" user "Ref Des/Silkscreen Top")
		(7 "B.SilkS" user "Ref Des/Silkscreen Bottom")
		(1 "F.Mask" user "Board Geometry/Soldermask Top")
		(3 "B.Mask" user "Board Geometry/Soldermask Bottom")
		(17 "Dwgs.User" user "User.Drawings")
		(19 "Cmts.User" user "User.Comments")
		(21 "Eco1.User" user "User.Eco1")
		(23 "Eco2.User" user "User.Eco2")
		(25 "Edge.Cuts" user "Board Geometry/Outline")
		(27 "Margin" user)
		(31 "F.CrtYd" user "Package Geometry/Place Bound Top")
		(29 "B.CrtYd" user "Package Geometry/Place Bound Bottom")
		(35 "F.Fab" user "Ref Des/Assembly Top")
		(33 "B.Fab" user "Ref Des/Assembly Bottom")
	)
	(footprint ""
		(layer "B.Cu")
		(at 116.225828 -256.012442 -90)
		(property "Reference" "C2458"
			(at 0 0 90)
			(layer "B.SilkS")
			(hide yes)
			(effects
				(font
					(size 1.27 1.27)
				)
				(justify mirror)
			)
		)
		(property "Value" ""
			(at 0 0 90)
			(layer "B.Fab")
			(effects
				(font
					(size 1.27 1.27)
				)
				(justify mirror)
			)
		)
		(duplicate_pad_numbers_are_jumpers no)
		(fp_line
			(start -0.7874 0.4064)
			(end 0.7874 0.4064)
			(stroke
				(width 0.1524)
				(type default)
			)
			(layer "B.SilkS")
		)
		(fp_line
			(start 0.7874 0.4064)
			(end 0.7874 -0.4064)
			(stroke
				(width 0.1524)
				(type default)
			)
			(layer "B.SilkS")
		)
		(fp_line
			(start -0.7874 -0.4064)
			(end -0.7874 0.4064)
			(stroke
				(width 0.1524)
				(type default)
			)
			(layer "B.SilkS")
		)
		(fp_line
			(start 0.7874 -0.4064)
			(end -0.7874 -0.4064)
			(stroke
				(width 0.1524)
				(type default)
			)
			(layer "B.SilkS")
		)
		(fp_line
			(start -0.67945 0.3048)
			(end -0.120396 0.3048)
			(stroke
				(width 0.1)
				(type default)
			)
			(layer "B.Fab")
		)
		(fp_line
			(start -0.120396 0.3048)
			(end -0.120396 0.2794)
			(stroke
				(width 0.1)
				(type default)
			)
			(layer "B.Fab")
		)
		(fp_line
			(start 0.12065 0.3048)
			(end 0.67945 0.3048)
			(stroke
				(width 0.1)
				(type default)
			)
			(layer "B.Fab")
		)
		(fp_line
			(start 0.67945 0.3048)
			(end 0.67945 -0.305054)
			(stroke
				(width 0.1)
				(type default)
			)
			(layer "B.Fab")
		)
		(fp_line
			(start -0.120396 0.2794)
			(end 0.12065 0.2794)
			(stroke
				(width 0.1)
				(type default)
			)
			(layer "B.Fab")
		)
		(fp_line
			(start 0.12065 0.2794)
			(end 0.12065 0.3048)
			(stroke
				(width 0.1)
				(type default)
			)
			(layer "B.Fab")
		)
		(fp_line
			(start -0.12065 -0.2794)
			(end -0.12065 -0.3048)
			(stroke
				(width 0.1)
				(type default)
			)
			(layer "B.Fab")
		)
		(fp_line
			(start 0.12065 -0.2794)
			(end -0.12065 -0.2794)
			(stroke
				(width 0.1)
				(type default)
			)
			(layer "B.Fab")
		)
		(fp_line
			(start -0.67945 -0.3048)
			(end -0.67945 0.3048)
			(stroke
				(width 0.1)
				(type default)
			)
			(layer "B.Fab")
		)
		(fp_line
			(start -0.12065 -0.3048)
			(end -0.67945 -0.3048)
			(stroke
				(width 0.1)
				(type default)
			)
			(layer "B.Fab")
		)
		(fp_line
			(start 0.12065 -0.305054)
			(end 0.12065 -0.2794)
			(stroke
				(width 0.1)
				(type default)
			)
			(layer "B.Fab")
		)
		(fp_line
			(start 0.67945 -0.305054)
			(end 0.12065 -0.305054)
			(stroke
				(width 0.1)
				(type default)
			)
			(layer "B.Fab")
		)
		(pad "1" smd circle
			(at 0.40005 0 90)
			(size 0 0)
			(layers "B.Cu" "B.Mask" "B.Paste")
			(net "PVDDCR_SOC_P1")
		)
		(pad "2" smd circle
			(at -0.40005 0 90)
			(size 0 0)
			(layers "B.Cu" "B.Mask" "B.Paste")
			(net "GND")
		)
	)
	(footprint ""
		(layer "B.Cu")
		(at 164.07257 -120.364758)
		(property "Reference" "R6093"
			(at 0 0 0)
			(layer "B.SilkS")
			(hide yes)
			(effects
				(font
					(size 1.27 1.27)
				)
				(justify mirror)
			)
		)
		(property "Value" ""
			(at 0 0 0)
			(layer "B.Fab")
			(effects
				(font
					(size 1.27 1.27)
				)
				(justify mirror)
			)
		)
		(duplicate_pad_numbers_are_jumpers no)
		(fp_line
			(start -0.7874 -0.4064)
			(end -0.7874 0.4064)
			(stroke
				(width 0.1524)
				(type default)
			)
			(layer "B.SilkS")
		)
		(fp_line
			(start -0.7874 0.4064)
			(end 0.7874 0.4064)
			(stroke
				(width 0.1524)
				(type default)
			)
			(layer "B.SilkS")
		)
		(fp_line
			(start 0.7874 -0.4064)
			(end -0.7874 -0.4064)
			(stroke
				(width 0.1524)
				(type default)
			)
			(layer "B.SilkS")
		)
		(fp_line
			(start 0.7874 0.4064)
			(end 0.7874 -0.4064)
			(stroke
				(width 0.1524)
				(type default)
			)
			(layer "B.SilkS")
		)
		(fp_line
			(start -0.67945 -0.3048)
			(end -0.67945 0.3048)
			(stroke
				(width 0.1)
				(type default)
			)
			(layer "B.Fab")
		)
		(fp_line
			(start -0.67945 0.3048)
			(end -0.120396 0.3048)
			(stroke
				(width 0.1)
				(type default)
			)
			(layer "B.Fab")
		)
		(fp_line
			(start -0.12065 -0.3048)
			(end -0.67945 -0.3048)
			(stroke
				(width 0.1)
				(type default)
			)
			(layer "B.Fab")
		)
		(fp_line
			(start -0.12065 -0.2794)
			(end -0.12065 -0.3048)
			(stroke
				(width 0.1)
				(type default)
			)
			(layer "B.Fab")
		)
		(fp_line
			(start -0.120396 0.2794)
			(end 0.12065 0.2794)
			(stroke
				(width 0.1)
				(type default)
			)
			(layer "B.Fab")
		)
		(fp_line
			(start -0.120396 0.3048)
			(end -0.120396 0.2794)
			(stroke
				(width 0.1)
				(type default)
			)
			(layer "B.Fab")
		)
		(fp_line
			(start 0.12065 -0.305054)
			(end 0.12065 -0.2794)
			(stroke
				(width 0.1)
				(type default)
			)
			(layer "B.Fab")
		)
		(fp_line
			(start 0.12065 -0.2794)
			(end -0.12065 -0.2794)
			(stroke
				(width 0.1)
				(type default)
			)
			(layer "B.Fab")
		)
		(fp_line
			(start 0.12065 0.2794)
			(end 0.12065 0.3048)
			(stroke
				(width 0.1)
				(type default)
			)
			(layer "B.Fab")
		)
		(fp_line
			(start 0.12065 0.3048)
			(end 0.67945 0.3048)
			(stroke
				(width 0.1)
				(type default)
			)
			(layer "B.Fab")
		)
		(fp_line
			(start 0.67945 -0.305054)
			(end 0.12065 -0.305054)
			(stroke
				(width 0.1)
				(type default)
			)
			(layer "B.Fab")
		)
		(fp_line
			(start 0.67945 0.3048)
			(end 0.67945 -0.305054)
			(stroke
				(width 0.1)
				(type default)
			)
			(layer "B.Fab")
		)
		(pad "1" smd circle
			(at 0.40005 0 180)
			(size 0 0)
			(layers "B.Cu" "B.Mask" "B.Paste")
			(net "SCM_SYS_PWROK_R")
		)
		(pad "2" smd circle
			(at -0.40005 0 180)
			(size 0 0)
			(layers "B.Cu" "B.Mask" "B.Paste")
			(net "SCM_SYS_PWROK_R2")
		)
	)
)
